(kicad_pcb
	(version 20260206)
	(generator "pcbnew")
	(generator_version "10.0")
	(general
		(thickness 1.6)
		(legacy_teardrops no)
	)
	(paper "A4")
	(title_block
		(title "01162023_DA0F0TEBIF0_F0T_Expander_BD_F_brd_V02_OCP.brd")
		(comment 1 "Grand Teton / footprints 224-229 of 9728")
	)
	(layers
		(0 "F.Cu" signal "TOP")
		(4 "In1.Cu" signal "GND")
		(6 "In2.Cu" signal "VCC")
		(8 "In3.Cu" signal "VCC1")
		(10 "In4.Cu" signal "GND1")
		(12 "In5.Cu" signal "IN1")
		(14 "In6.Cu" signal "GND2")
		(16 "In7.Cu" signal "IN2")
		(18 "In8.Cu" signal "GND3")
		(20 "In9.Cu" signal "IN3")
		(22 "In10.Cu" signal "GND4")
		(24 "In11.Cu" signal "IN4")
		(26 "In12.Cu" signal "GND5")
		(28 "In13.Cu" signal "IN5")
		(30 "In14.Cu" signal "GND6")
		(32 "In15.Cu" signal "IN6")
		(34 "In16.Cu" signal "GND7")
		(2 "B.Cu" signal "BOTTOM")
		(9 "F.Adhes" user "F.Adhesive")
		(11 "B.Adhes" user "B.Adhesive")
		(13 "F.Paste" user "Package Geometry/Pastemask Top")
		(15 "B.Paste" user "Package Geometry/Pastemask Bottom")
		(5 "F.SilkS" user "Ref Des/Silkscreen Top")
		(7 "B.SilkS" user "Ref Des/Silkscreen Bottom")
		(1 "F.Mask" user "Board Geometry/Soldermask Top")
		(3 "B.Mask" user "Board Geometry/Soldermask Bottom")
		(17 "Dwgs.User" user "User.Drawings")
		(19 "Cmts.User" user "User.Comments")
		(21 "Eco1.User" user "User.Eco1")
		(23 "Eco2.User" user "User.Eco2")
		(25 "Edge.Cuts" user "Board Geometry/Outline")
		(27 "Margin" user)
		(31 "F.CrtYd" user "Package Geometry/Place Bound Top")
		(29 "B.CrtYd" user "Package Geometry/Place Bound Bottom")
		(35 "F.Fab" user "Ref Des/Assembly Top")
		(33 "B.Fab" user "Ref Des/Assembly Bottom")
	)
	(footprint ""
		(layer "F.Cu")
		(at 127.274828 -251.759974 -90)
		(property "Reference" "PR73"
			(at 0 0 270)
			(layer "F.SilkS")
			(hide yes)
			(effects
				(font
					(size 1.27 1.27)
				)
			)
		)
		(property "Value" ""
			(at 0 0 270)
			(layer "F.Fab")
			(effects
				(font
					(size 1.27 1.27)
				)
			)
		)
		(duplicate_pad_numbers_are_jumpers no)
		(fp_line
			(start -0.7874 0.4064)
			(end -0.7874 -0.4064)
			(stroke
				(width 0.1524)
				(type default)
			)
			(layer "F.SilkS")
		)
		(fp_line
			(start 0.7874 0.4064)
			(end -0.7874 0.4064)
			(stroke
				(width 0.1524)
				(type default)
			)
			(layer "F.SilkS")
		)
		(fp_line
			(start -0.7874 -0.4064)
			(end 0.7874 -0.4064)
			(stroke
				(width 0.1524)
				(type default)
			)
			(layer "F.SilkS")
		)
		(fp_line
			(start 0.7874 -0.4064)
			(end 0.7874 0.4064)
			(stroke
				(width 0.1524)
				(type default)
			)
			(layer "F.SilkS")
		)
		(fp_line
			(start -0.67945 0.3048)
			(end -0.67945 -0.305054)
			(stroke
				(width 0.1)
				(type default)
			)
			(layer "F.Fab")
		)
		(fp_line
			(start -0.12065 0.3048)
			(end -0.67945 0.3048)
			(stroke
				(width 0.1)
				(type default)
			)
			(layer "F.Fab")
		)
		(fp_line
			(start 0.120396 0.3048)
			(end 0.120396 0.2794)
			(stroke
				(width 0.1)
				(type default)
			)
			(layer "F.Fab")
		)
		(fp_line
			(start 0.67945 0.3048)
			(end 0.120396 0.3048)
			(stroke
				(width 0.1)
				(type default)
			)
			(layer "F.Fab")
		)
		(fp_line
			(start -0.12065 0.2794)
			(end -0.12065 0.3048)
			(stroke
				(width 0.1)
				(type default)
			)
			(layer "F.Fab")
		)
		(fp_line
			(start 0.120396 0.2794)
			(end -0.12065 0.2794)
			(stroke
				(width 0.1)
				(type default)
			)
			(layer "F.Fab")
		)
		(fp_line
			(start -0.12065 -0.2794)
			(end 0.12065 -0.2794)
			(stroke
				(width 0.1)
				(type default)
			)
			(layer "F.Fab")
		)
		(fp_line
			(start 0.12065 -0.2794)
			(end 0.12065 -0.3048)
			(stroke
				(width 0.1)
				(type default)
			)
			(layer "F.Fab")
		)
		(fp_line
			(start 0.12065 -0.3048)
			(end 0.67945 -0.3048)
			(stroke
				(width 0.1)
				(type default)
			)
			(layer "F.Fab")
		)
		(fp_line
			(start 0.67945 -0.3048)
			(end 0.67945 0.3048)
			(stroke
				(width 0.1)
				(type default)
			)
			(layer "F.Fab")
		)
		(fp_line
			(start -0.67945 -0.305054)
			(end -0.12065 -0.305054)
			(stroke
				(width 0.1)
				(type default)
			)
			(layer "F.Fab")
		)
		(fp_line
			(start -0.12065 -0.305054)
			(end -0.12065 -0.2794)
			(stroke
				(width 0.1)
				(type default)
			)
			(layer "F.Fab")
		)
		(pad "1" smd circle
			(at -0.40005 0 270)
			(size 0 0)
			(layers "F.Cu" "F.Mask" "F.Paste")
			(net "SMB_PJP1_SDA")
		)
		(pad "2" smd circle
			(at 0.40005 0 270)
			(size 0 0)
			(layers "F.Cu" "F.Mask" "F.Paste")
			(net "SMB_BIC_I2C6_MUX_VR_R_SDA")
		)
	)
	(footprint ""
		(layer "F.Cu")
		(at 148.570442 -252.356874 -90)
		(property "Reference" "R1297"
			(at 0 0 270)
			(layer "F.SilkS")
			(hide yes)
			(effects
				(font
					(size 1.27 1.27)
				)
			)
		)
		(property "Value" ""
			(at 0 0 270)
			(layer "F.Fab")
			(effects
				(font
					(size 1.27 1.27)
				)
			)
		)
		(duplicate_pad_numbers_are_jumpers no)
		(fp_line
			(start -0.7874 0.4064)
			(end -0.7874 -0.4064)
			(stroke
				(width 0.1524)
				(type default)
			)
			(layer "F.SilkS")
		)
		(fp_line
			(start 0.7874 0.4064)
			(end -0.7874 0.4064)
			(stroke
				(width 0.1524)
				(type default)
			)
			(layer "F.SilkS")
		)
		(fp_line
			(start -0.7874 -0.4064)
			(end 0.7874 -0.4064)
			(stroke
				(width 0.1524)
				(type default)
			)
			(layer "F.SilkS")
		)
		(fp_line
			(start 0.7874 -0.4064)
			(end 0.7874 0.4064)
			(stroke
				(width 0.1524)
				(type default)
			)
			(layer "F.SilkS")
		)
		(fp_line
			(start -0.67945 0.3048)
			(end -0.67945 -0.305054)
			(stroke
				(width 0.1)
				(type default)
			)
			(layer "F.Fab")
		)
		(fp_line
			(start -0.12065 0.3048)
			(end -0.67945 0.3048)
			(stroke
				(width 0.1)
				(type default)
			)
			(layer "F.Fab")
		)
		(fp_line
			(start 0.120396 0.3048)
			(end 0.120396 0.2794)
			(stroke
				(width 0.1)
				(type default)
			)
			(layer "F.Fab")
		)
		(fp_line
			(start 0.67945 0.3048)
			(end 0.120396 0.3048)
			(stroke
				(width 0.1)
				(type default)
			)
			(layer "F.Fab")
		)
		(fp_line
			(start -0.12065 0.2794)
			(end -0.12065 0.3048)
			(stroke
				(width 0.1)
				(type default)
			)
			(layer "F.Fab")
		)
		(fp_line
			(start 0.120396 0.2794)
			(end -0.12065 0.2794)
			(stroke
				(width 0.1)
				(type default)
			)
			(layer "F.Fab")
		)
		(fp_line
			(start -0.12065 -0.2794)
			(end 0.12065 -0.2794)
			(stroke
				(width 0.1)
				(type default)
			)
			(layer "F.Fab")
		)
		(fp_line
			(start 0.12065 -0.2794)
			(end 0.12065 -0.3048)
			(stroke
				(width 0.1)
				(type default)
			)
			(layer "F.Fab")
		)
		(fp_line
			(start 0.12065 -0.3048)
			(end 0.67945 -0.3048)
			(stroke
				(width 0.1)
				(type default)
			)
			(layer "F.Fab")
		)
		(fp_line
			(start 0.67945 -0.3048)
			(end 0.67945 0.3048)
			(stroke
				(width 0.1)
				(type default)
			)
			(layer "F.Fab")
		)
		(fp_line
			(start -0.67945 -0.305054)
			(end -0.12065 -0.305054)
			(stroke
				(width 0.1)
				(type default)
			)
			(layer "F.Fab")
		)
		(fp_line
			(start -0.12065 -0.305054)
			(end -0.12065 -0.2794)
			(stroke
				(width 0.1)
				(type default)
			)
			(layer "F.Fab")
		)
		(pad "1" smd circle
			(at -0.40005 0 270)
			(size 0 0)
			(layers "F.Cu" "F.Mask" "F.Paste")
			(net "GND")
		)
		(pad "2" smd circle
			(at 0.40005 0 270)
			(size 0 0)
			(layers "F.Cu" "F.Mask" "F.Paste")
			(net "PEX1_MODE_SEL8")
		)
	)
	(footprint ""
		(layer "F.Cu")
		(at 193.207386 -81.09966)
		(property "Reference" "Q4"
			(at -1.996186 -1.70307 0)
			(unlocked yes)
			(layer "F.SilkS")
			(effects
				(font
					(size 0.7874 0.5842)
					(thickness 0.1524)
				)
				(justify left)
			)
		)
		(property "Value" ""
			(at 0 0 0)
			(layer "F.Fab")
			(effects
				(font
					(size 1.27 1.27)
				)
			)
		)
		(duplicate_pad_numbers_are_jumpers no)
		(fp_line
			(start -1.38176 -1.100074)
			(end -1.38176 1.100074)
			(stroke
				(width 0.1524)
				(type default)
			)
			(layer "F.SilkS")
		)
		(fp_line
			(start -1.38176 1.100074)
			(end 1.38176 1.100074)
			(stroke
				(width 0.1524)
				(type default)
			)
			(layer "F.SilkS")
		)
		(fp_line
			(start -0.592074 -1.100074)
			(end -1.38176 -1.100074)
			(stroke
				(width 0.1524)
				(type default)
			)
			(layer "F.SilkS")
		)
		(fp_line
			(start 0 -0.508)
			(end -0.592074 -1.100074)
			(stroke
				(width 0.1524)
				(type default)
			)
			(layer "F.SilkS")
		)
		(fp_line
			(start 0.592074 -1.100074)
			(end 0 -0.508)
			(stroke
				(width 0.1524)
				(type default)
			)
			(layer "F.SilkS")
		)
		(fp_line
			(start 1.38176 -1.100074)
			(end 0.592074 -1.100074)
			(stroke
				(width 0.1524)
				(type default)
			)
			(layer "F.SilkS")
		)
		(fp_line
			(start 1.38176 1.100074)
			(end 1.38176 -1.100074)
			(stroke
				(width 0.1524)
				(type default)
			)
			(layer "F.SilkS")
		)
		(fp_poly
			(pts
				(xy -1.9431 -0.870204) (xy -1.50241 -0.649986) (xy -1.9431 -0.429768)
			)
			(stroke
				(width 0)
				(type default)
			)
			(fill yes)
			(layer "F.SilkS")
		)
		(fp_line
			(start -0.674878 -1.100074)
			(end -0.674878 1.100074)
			(stroke
				(width 0.1)
				(type default)
			)
			(layer "F.Fab")
		)
		(fp_line
			(start -0.674878 1.100074)
			(end 0.674878 1.100074)
			(stroke
				(width 0.1)
				(type default)
			)
			(layer "F.Fab")
		)
		(fp_line
			(start 0.674878 -1.100074)
			(end -0.674878 -1.100074)
			(stroke
				(width 0.1)
				(type default)
			)
			(layer "F.Fab")
		)
		(fp_line
			(start 0.674878 1.100074)
			(end 0.674878 -1.100074)
			(stroke
				(width 0.1)
				(type default)
			)
			(layer "F.Fab")
		)
		(fp_poly
			(pts
				(xy -1.9431 -0.870204) (xy -1.50241 -0.649986) (xy -1.9431 -0.429768)
			)
			(stroke
				(width 0)
				(type default)
			)
			(fill yes)
			(layer "F.Fab")
		)
		(pad "1" smd rect
			(at -0.94996 -0.649986 270)
			(size 0.4318 0.6096)
			(layers "F.Cu" "F.Mask" "F.Paste")
			(net "GND")
		)
		(pad "2" smd rect
			(at -0.94996 0 270)
			(size 0.4318 0.6096)
			(layers "F.Cu" "F.Mask" "F.Paste")
			(net "HP_NIC3_HSC_PWRGD_N")
		)
		(pad "3" smd rect
			(at -0.94996 0.649986 270)
			(size 0.4318 0.6096)
			(layers "F.Cu" "F.Mask" "F.Paste")
			(net "HP_NIC3_HSC_PWRGD_N")
		)
		(pad "4" smd rect
			(at 0.94996 0.649986 270)
			(size 0.4318 0.6096)
			(layers "F.Cu" "F.Mask" "F.Paste")
			(net "GND")
		)
		(pad "5" smd rect
			(at 0.94996 0 270)
			(size 0.4318 0.6096)
			(layers "F.Cu" "F.Mask" "F.Paste")
			(net "PWRGD_P12V_NIC3_R")
		)
		(pad "6" smd rect
			(at 0.94996 -0.649986 270)
			(size 0.4318 0.6096)
			(layers "F.Cu" "F.Mask" "F.Paste")
			(net "HP_NIC3_PWRGD_R")
		)
	)
	(footprint ""
		(layer "F.Cu")
		(at 230.377746 -118.984268 -90)
		(property "Reference" "PC631"
			(at 0 0 270)
			(layer "F.SilkS")
			(hide yes)
			(effects
				(font
					(size 1.27 1.27)
				)
			)
		)
		(property "Value" ""
			(at 0 0 270)
			(layer "F.Fab")
			(effects
				(font
					(size 1.27 1.27)
				)
			)
		)
		(duplicate_pad_numbers_are_jumpers no)
		(fp_line
			(start -1.2954 0.5842)
			(end -1.2954 -0.5842)
			(stroke
				(width 0.1524)
				(type default)
			)
			(layer "F.SilkS")
		)
		(fp_line
			(start 1.2954 0.5842)
			(end -1.2954 0.5842)
			(stroke
				(width 0.1524)
				(type default)
			)
			(layer "F.SilkS")
		)
		(fp_line
			(start -1.2954 -0.5842)
			(end 1.2954 -0.5842)
			(stroke
				(width 0.1524)
				(type default)
			)
			(layer "F.SilkS")
		)
		(fp_line
			(start 1.2954 -0.5842)
			(end 1.2954 0.5842)
			(stroke
				(width 0.1524)
				(type default)
			)
			(layer "F.SilkS")
		)
		(fp_line
			(start -0.8636 0.4572)
			(end -0.8636 0.4064)
			(stroke
				(width 0.1)
				(type default)
			)
			(layer "F.Fab")
		)
		(fp_line
			(start 0.8636 0.4572)
			(end -0.8636 0.4572)
			(stroke
				(width 0.1)
				(type default)
			)
			(layer "F.Fab")
		)
		(fp_line
			(start -1.1938 0.4064)
			(end -1.1938 -0.4064)
			(stroke
				(width 0.1)
				(type default)
			)
			(layer "F.Fab")
		)
		(fp_line
			(start -0.8636 0.4064)
			(end -1.1938 0.4064)
			(stroke
				(width 0.1)
				(type default)
			)
			(layer "F.Fab")
		)
		(fp_line
			(start 0.8636 0.4064)
			(end 0.8636 0.4572)
			(stroke
				(width 0.1)
				(type default)
			)
			(layer "F.Fab")
		)
		(fp_line
			(start 1.1938 0.4064)
			(end 0.8636 0.4064)
			(stroke
				(width 0.1)
				(type default)
			)
			(layer "F.Fab")
		)
		(fp_line
			(start -1.1938 -0.4064)
			(end -0.8636 -0.4064)
			(stroke
				(width 0.1)
				(type default)
			)
			(layer "F.Fab")
		)
		(fp_line
			(start -0.8636 -0.4064)
			(end -0.8636 -0.4572)
			(stroke
				(width 0.1)
				(type default)
			)
			(layer "F.Fab")
		)
		(fp_line
			(start 0.8636 -0.4064)
			(end 1.1938 -0.4064)
			(stroke
				(width 0.1)
				(type default)
			)
			(layer "F.Fab")
		)
		(fp_line
			(start 1.1938 -0.4064)
			(end 1.1938 0.4064)
			(stroke
				(width 0.1)
				(type default)
			)
			(layer "F.Fab")
		)
		(fp_line
			(start -0.8636 -0.4572)
			(end 0.8636 -0.4572)
			(stroke
				(width 0.1)
				(type default)
			)
			(layer "F.Fab")
		)
		(fp_line
			(start 0.8636 -0.4572)
			(end 0.8636 -0.4064)
			(stroke
				(width 0.1)
				(type default)
			)
			(layer "F.Fab")
		)
		(pad "1" smd rect
			(at -0.7366 0 180)
			(size 0.7112 0.8128)
			(layers "F.Cu" "F.Mask" "F.Paste")
			(net "GND")
		)
		(pad "2" smd rect
			(at 0.7366 0 180)
			(size 0.7112 0.8128)
			(layers "F.Cu" "F.Mask" "F.Paste")
			(net "P12V_NIC3_CO_AVIN_PD")
		)
	)
	(footprint ""
		(layer "F.Cu")
		(at 122.88139 -262.04672 180)
		(property "Reference" "PC49"
			(at 0 0 180)
			(layer "F.SilkS")
			(hide yes)
			(effects
				(font
					(size 1.27 1.27)
				)
			)
		)
		(property "Value" ""
			(at 0 0 180)
			(layer "F.Fab")
			(effects
				(font
					(size 1.27 1.27)
				)
			)
		)
		(duplicate_pad_numbers_are_jumpers no)
		(fp_line
			(start 0.7874 0.4064)
			(end -0.7874 0.4064)
			(stroke
				(width 0.1524)
				(type default)
			)
			(layer "F.SilkS")
		)
		(fp_line
			(start 0.7874 -0.4064)
			(end 0.7874 0.4064)
			(stroke
				(width 0.1524)
				(type default)
			)
			(layer "F.SilkS")
		)
		(fp_line
			(start -0.7874 0.4064)
			(end -0.7874 -0.4064)
			(stroke
				(width 0.1524)
				(type default)
			)
			(layer "F.SilkS")
		)
		(fp_line
			(start -0.7874 -0.4064)
			(end 0.7874 -0.4064)
			(stroke
				(width 0.1524)
				(type default)
			)
			(layer "F.SilkS")
		)
		(fp_line
			(start 0.67945 0.3048)
			(end 0.120396 0.3048)
			(stroke
				(width 0.1)
				(type default)
			)
			(layer "F.Fab")
		)
		(fp_line
			(start 0.67945 -0.3048)
			(end 0.67945 0.3048)
			(stroke
				(width 0.1)
				(type default)
			)
			(layer "F.Fab")
		)
		(fp_line
			(start 0.12065 -0.2794)
			(end 0.12065 -0.3048)
			(stroke
				(width 0.1)
				(type default)
			)
			(layer "F.Fab")
		)
		(fp_line
			(start 0.12065 -0.3048)
			(end 0.67945 -0.3048)
			(stroke
				(width 0.1)
				(type default)
			)
			(layer "F.Fab")
		)
		(fp_line
			(start 0.120396 0.3048)
			(end 0.120396 0.2794)
			(stroke
				(width 0.1)
				(type default)
			)
			(layer "F.Fab")
		)
		(fp_line
			(start 0.120396 0.2794)
			(end -0.12065 0.2794)
			(stroke
				(width 0.1)
				(type default)
			)
			(layer "F.Fab")
		)
		(fp_line
			(start -0.12065 0.3048)
			(end -0.67945 0.3048)
			(stroke
				(width 0.1)
				(type default)
			)
			(layer "F.Fab")
		)
		(fp_line
			(start -0.12065 0.2794)
			(end -0.12065 0.3048)
			(stroke
				(width 0.1)
				(type default)
			)
			(layer "F.Fab")
		)
		(fp_line
			(start -0.12065 -0.2794)
			(end 0.12065 -0.2794)
			(stroke
				(width 0.1)
				(type default)
			)
			(layer "F.Fab")
		)
		(fp_line
			(start -0.12065 -0.305054)
			(end -0.12065 -0.2794)
			(stroke
				(width 0.1)
				(type default)
			)
			(layer "F.Fab")
		)
		(fp_line
			(start -0.67945 0.3048)
			(end -0.67945 -0.305054)
			(stroke
				(width 0.1)
				(type default)
			)
			(layer "F.Fab")
		)
		(fp_line
			(start -0.67945 -0.305054)
			(end -0.12065 -0.305054)
			(stroke
				(width 0.1)
				(type default)
			)
			(layer "F.Fab")
		)
		(pad "1" smd circle
			(at -0.40005 0 180)
			(size 0 0)
			(layers "F.Cu" "F.Mask" "F.Paste")
			(net "P0V8_PEX0_VSEN0")
		)
		(pad "2" smd circle
			(at 0.40005 0 180)
			(size 0 0)
			(layers "F.Cu" "F.Mask" "F.Paste")
			(net "SH_P0V8_PEX0_RGND0")
		)
	)
	(footprint ""
		(layer "F.Cu")
		(at 231.844596 -274.487386)
		(property "Reference" "R784"
			(at 0 0 0)
			(layer "F.SilkS")
			(hide yes)
			(effects
				(font
					(size 1.27 1.27)
				)
			)
		)
		(property "Value" ""
			(at 0 0 0)
			(layer "F.Fab")
			(effects
				(font
					(size 1.27 1.27)
				)
			)
		)
		(duplicate_pad_numbers_are_jumpers no)
		(fp_line
			(start -0.7874 -0.4064)
			(end 0.7874 -0.4064)
			(stroke
				(width 0.1524)
				(type default)
			)
			(layer "F.SilkS")
		)
		(fp_line
			(start -0.7874 0.4064)
			(end -0.7874 -0.4064)
			(stroke
				(width 0.1524)
				(type default)
			)
			(layer "F.SilkS")
		)
		(fp_line
			(start 0.7874 -0.4064)
			(end 0.7874 0.4064)
			(stroke
				(width 0.1524)
				(type default)
			)
			(layer "F.SilkS")
		)
		(fp_line
			(start 0.7874 0.4064)
			(end -0.7874 0.4064)
			(stroke
				(width 0.1524)
				(type default)
			)
			(layer "F.SilkS")
		)
		(fp_line
			(start -0.67945 -0.305054)
			(end -0.12065 -0.305054)
			(stroke
				(width 0.1)
				(type default)
			)
			(layer "F.Fab")
		)
		(fp_line
			(start -0.67945 0.3048)
			(end -0.67945 -0.305054)
			(stroke
				(width 0.1)
				(type default)
			)
			(layer "F.Fab")
		)
		(fp_line
			(start -0.12065 -0.305054)
			(end -0.12065 -0.2794)
			(stroke
				(width 0.1)
				(type default)
			)
			(layer "F.Fab")
		)
		(fp_line
			(start -0.12065 -0.2794)
			(end 0.12065 -0.2794)
			(stroke
				(width 0.1)
				(type default)
			)
			(layer "F.Fab")
		)
		(fp_line
			(start -0.12065 0.2794)
			(end -0.12065 0.3048)
			(stroke
				(width 0.1)
				(type default)
			)
			(layer "F.Fab")
		)
		(fp_line
			(start -0.12065 0.3048)
			(end -0.67945 0.3048)
			(stroke
				(width 0.1)
				(type default)
			)
			(layer "F.Fab")
		)
		(fp_line
			(start 0.120396 0.2794)
			(end -0.12065 0.2794)
			(stroke
				(width 0.1)
				(type default)
			)
			(layer "F.Fab")
		)
		(fp_line
			(start 0.120396 0.3048)
			(end 0.120396 0.2794)
			(stroke
				(width 0.1)
				(type default)
			)
			(layer "F.Fab")
		)
		(fp_line
			(start 0.12065 -0.3048)
			(end 0.67945 -0.3048)
			(stroke
				(width 0.1)
				(type default)
			)
			(layer "F.Fab")
		)
		(fp_line
			(start 0.12065 -0.2794)
			(end 0.12065 -0.3048)
			(stroke
				(width 0.1)
				(type default)
			)
			(layer "F.Fab")
		)
		(fp_line
			(start 0.67945 -0.3048)
			(end 0.67945 0.3048)
			(stroke
				(width 0.1)
				(type default)
			)
			(layer "F.Fab")
		)
		(fp_line
			(start 0.67945 0.3048)
			(end 0.120396 0.3048)
			(stroke
				(width 0.1)
				(type default)
			)
			(layer "F.Fab")
		)
		(pad "1" smd circle
			(at -0.40005 0)
			(size 0 0)
			(layers "F.Cu" "F.Mask" "F.Paste")
			(net "PEX1_P1V25_ADC_A1")
		)
		(pad "2" smd circle
			(at 0.40005 0)
			(size 0 0)
			(layers "F.Cu" "F.Mask" "F.Paste")
			(net "GND")
		)
	)
)
